(kicad_pcb
	(version 20241229)
	(generator "pcbnew")
	(generator_version "9.0")
	(general
		(thickness 1.711)
		(legacy_teardrops no)
	)
	(paper "A4")
	(title_block
		(title "Antmicro Baseboard for Jetson AGX Thor")
		(date "2026-02-18")
		(rev "1.1.0")
		(company "Antmicro Ltd")
		(comment 1 "www.antmicro.com")
		(comment 9 "footprints 646-649 of 1170")
	)
	(layers
		(0 "F.Cu" signal)
		(4 "In1.Cu" signal)
		(6 "In2.Cu" signal)
		(8 "In3.Cu" signal)
		(10 "In4.Cu" jumper)
		(12 "In5.Cu" signal)
		(14 "In6.Cu" signal)
		(16 "In7.Cu" signal)
		(18 "In8.Cu" signal)
		(2 "B.Cu" signal)
		(9 "F.Adhes" user "F.Adhesive")
		(11 "B.Adhes" user "B.Adhesive")
		(13 "F.Paste" user)
		(15 "B.Paste" user)
		(5 "F.SilkS" user "F.Silkscreen")
		(7 "B.SilkS" user "B.Silkscreen")
		(1 "F.Mask" user)
		(3 "B.Mask" user)
		(17 "Dwgs.User" user "User.Drawings")
		(19 "Cmts.User" user "User.Comments")
		(21 "Eco1.User" user "User.Eco1")
		(23 "Eco2.User" user "User.Eco2")
		(25 "Edge.Cuts" user)
		(27 "Margin" user)
		(31 "F.CrtYd" user "F.Courtyard")
		(29 "B.CrtYd" user "B.Courtyard")
		(35 "F.Fab" user)
		(33 "B.Fab" user)
	)
	(footprint "antmicro-footprints:C_0402_1005Metric"
		(layer "B.Cu")
		(at 110.25 97.5)
		(descr "Capacitor SMD 0402")
		(tags "capacitor SMD 0402")
		(property "Reference" "C188"
			(at -0.95 -0.4 0)
			(layer "B.SilkS")
			(effects
				(font
					(size 0.7 0.7)
					(thickness 0.15)
				)
				(justify left top mirror)
			)
		)
		(property "Value" "C_220n_0402"
			(at -1.022927 -2.155213 0)
			(layer "B.Fab")
			(effects
				(font
					(size 0.7 0.7)
					(thickness 0.15)
				)
				(justify right top mirror)
			)
		)
		(property "Datasheet" "https://www.yageo.com/en/Chart/Download/pdf/CC0402KRX5R6BB224"
			(at 0 0 0)
			(layer "B.Fab")
			(hide yes)
			(effects
				(font
					(size 1.27 1.27)
					(thickness 0.15)
				)
				(justify mirror)
			)
		)
		(property "Description" "SMD Multilayer Ceramic Capacitor, 0.22 µF, 10 V, 0402 [1005 Metric], ± 10%, X5R, CC Series"
			(at 0 0 0)
			(layer "B.Fab")
			(hide yes)
			(effects
				(font
					(size 1.27 1.27)
					(thickness 0.15)
				)
				(justify mirror)
			)
		)
		(property "MPN" "CC0402KRX5R6BB224"
			(at 0 0 0)
			(unlocked yes)
			(layer "B.Fab")
			(hide yes)
			(effects
				(font
					(size 1 1)
					(thickness 0.15)
				)
				(justify mirror)
			)
		)
		(property "Val" "220n"
			(at 0 0 0)
			(unlocked yes)
			(layer "B.Fab")
			(hide yes)
			(effects
				(font
					(size 1 1)
					(thickness 0.15)
				)
				(justify mirror)
			)
		)
		(property "Voltage" "25V"
			(at 0 0 0)
			(unlocked yes)
			(layer "B.Fab")
			(hide yes)
			(effects
				(font
					(size 1 1)
					(thickness 0.15)
				)
				(justify mirror)
			)
		)
		(property "Dielectric" "X7R"
			(at 0 0 0)
			(unlocked yes)
			(layer "B.Fab")
			(hide yes)
			(effects
				(font
					(size 1 1)
					(thickness 0.15)
				)
				(justify mirror)
			)
		)
		(property "Manufacturer" "YAGEO"
			(at 0 0 0)
			(unlocked yes)
			(layer "B.Fab")
			(hide yes)
			(effects
				(font
					(size 1 1)
					(thickness 0.15)
				)
				(justify mirror)
			)
		)
		(property "License" "Apache-2.0"
			(at 0 0 0)
			(unlocked yes)
			(layer "B.Fab")
			(hide yes)
			(effects
				(font
					(size 1 1)
					(thickness 0.15)
				)
				(justify mirror)
			)
		)
		(property "Author" "Antmicro"
			(at 0 0 0)
			(unlocked yes)
			(layer "B.Fab")
			(hide yes)
			(effects
				(font
					(size 1 1)
					(thickness 0.15)
				)
				(justify mirror)
			)
		)
		(property "Public" "False"
			(at 0 0 0)
			(unlocked yes)
			(layer "B.Fab")
			(hide yes)
			(effects
				(font
					(size 1 1)
					(thickness 0.15)
				)
				(justify mirror)
			)
		)
		(sheetname "/M.2/")
		(sheetfile "m2.kicad_sch")
		(attr smd)
		(fp_poly
			(pts
				(xy -0.925 0.47) (xy -0.925 -0.47) (xy 0.925 -0.47) (xy 0.925 0.47)
			)
			(stroke
				(width 0.05)
				(type default)
			)
			(fill no)
			(layer "B.CrtYd")
		)
		(fp_line
			(start -0.494 -0.248)
			(end -0.494 0.25)
			(stroke
				(width 0.15)
				(type solid)
			)
			(layer "B.Fab")
		)
		(fp_line
			(start -0.494 0.25)
			(end 0.504 0.25)
			(stroke
				(width 0.15)
				(type solid)
			)
			(layer "B.Fab")
		)
		(fp_line
			(start 0.504 -0.248)
			(end -0.494 -0.248)
			(stroke
				(width 0.15)
				(type solid)
			)
			(layer "B.Fab")
		)
		(fp_line
			(start 0.504 0.25)
			(end 0.504 -0.248)
			(stroke
				(width 0.15)
				(type solid)
			)
			(layer "B.Fab")
		)
		(fp_text user "License: Apache-2.0"
			(at -0.939 -5.799 0)
			(layer "B.Fab")
			(effects
				(font
					(size 0.7 0.7)
					(thickness 0.15)
				)
				(justify right top mirror)
			)
		)
		(fp_text user "Author: Antmicro"
			(at -0.939 -3.399 0)
			(layer "B.Fab")
			(effects
				(font
					(size 0.7 0.7)
					(thickness 0.15)
				)
				(justify right top mirror)
			)
		)
		(fp_text user "${REFERENCE}"
			(at -0.939 -4.599 0)
			(layer "B.Fab")
			(effects
				(font
					(size 0.7 0.7)
					(thickness 0.15)
				)
				(justify right top mirror)
			)
		)
		(pad "1" smd roundrect
			(at -0.48 0)
			(size 0.59 0.64)
			(layers "B.Cu" "B.Mask" "B.Paste")
			(roundrect_rratio 0.25)
			(net 439 "/M.2/PCIe_{C5x4}.TX3-")
			(pintype "passive")
		)
		(pad "2" smd roundrect
			(at 0.48 0)
			(size 0.59 0.64)
			(layers "B.Cu" "B.Mask" "B.Paste")
			(roundrect_rratio 0.25)
			(net 436 "/M.2/M2_M_PET3_N")
			(pintype "passive")
		)
	)
	(footprint "antmicro-footprints:SOT-523"
		(layer "B.Cu")
		(at 218.192132 97.084486 -90)
		(property "Reference" "Q35"
			(at 2.015514 -1.007868 0)
			(layer "B.SilkS")
			(effects
				(font
					(size 0.7 0.7)
					(thickness 0.15)
				)
				(justify left bottom mirror)
			)
		)
		(property "Value" "DMG1012T-7"
			(at 0.1 -1.824 90)
			(layer "B.Fab")
			(effects
				(font
					(size 0.7 0.7)
					(thickness 0.15)
				)
				(justify left bottom mirror)
			)
		)
		(property "Datasheet" "https://www.diodes.com/assets/Datasheets/ds31783.pdf"
			(at 0 0 90)
			(layer "B.Fab")
			(hide yes)
			(effects
				(font
					(size 1.27 1.27)
					(thickness 0.15)
				)
				(justify mirror)
			)
		)
		(property "Description" "Power MOSFET, N Channel, 20 V, 630 mA, 0.3 ohm, SOT-523, Surface Mount"
			(at 0 0 90)
			(layer "B.Fab")
			(hide yes)
			(effects
				(font
					(size 1.27 1.27)
					(thickness 0.15)
				)
				(justify mirror)
			)
		)
		(property "MPN" "DMG1012T-7"
			(at 0 0 90)
			(unlocked yes)
			(layer "B.Fab")
			(hide yes)
			(effects
				(font
					(size 1 1)
					(thickness 0.15)
				)
				(justify mirror)
			)
		)
		(property "Manufacturer" "Diodes Incorporated"
			(at 0 0 90)
			(unlocked yes)
			(layer "B.Fab")
			(hide yes)
			(effects
				(font
					(size 1 1)
					(thickness 0.15)
				)
				(justify mirror)
			)
		)
		(property "Author" "Antmicro"
			(at 0 0 90)
			(unlocked yes)
			(layer "B.Fab")
			(hide yes)
			(effects
				(font
					(size 1 1)
					(thickness 0.15)
				)
				(justify mirror)
			)
		)
		(property "License" "Apache-2.0"
			(at 0 0 90)
			(unlocked yes)
			(layer "B.Fab")
			(hide yes)
			(effects
				(font
					(size 1 1)
					(thickness 0.15)
				)
				(justify mirror)
			)
		)
		(sheetname "/USB DP Alt mode/")
		(sheetfile "usb_dp.kicad_sch")
		(attr smd)
		(fp_line
			(start -0.725 0.551)
			(end -0.277 0.551)
			(stroke
				(width 0.15)
				(type solid)
			)
			(layer "B.SilkS")
		)
		(fp_line
			(start -0.277 0.551)
			(end -0.277 0.75)
			(stroke
				(width 0.15)
				(type solid)
			)
			(layer "B.SilkS")
		)
		(fp_line
			(start -0.927 0.351)
			(end -0.725 0.551)
			(stroke
				(width 0.15)
				(type solid)
			)
			(layer "B.SilkS")
		)
		(fp_line
			(start -0.927 0.051)
			(end -0.927 0.351)
			(stroke
				(width 0.15)
				(type solid)
			)
			(layer "B.SilkS")
		)
		(fp_circle
			(center -0.9652 -0.9652)
			(end -0.9152 -0.9652)
			(stroke
				(width 0.15)
				(type solid)
			)
			(fill yes)
			(layer "B.SilkS")
		)
		(fp_line
			(start -1.12 1.16)
			(end 1.1 1.16)
			(stroke
				(width 0.05)
				(type solid)
			)
			(layer "B.CrtYd")
		)
		(fp_line
			(start -1.12 1.16)
			(end -1.12 -1.15)
			(stroke
				(width 0.05)
				(type solid)
			)
			(layer "B.CrtYd")
		)
		(fp_line
			(start 1.1 1.16)
			(end 1.1 -1.15)
			(stroke
				(width 0.05)
				(type solid)
			)
			(layer "B.CrtYd")
		)
		(fp_line
			(start -1.12 -1.15)
			(end 1.1 -1.15)
			(stroke
				(width 0.05)
				(type solid)
			)
			(layer "B.CrtYd")
		)
		(fp_line
			(start -0.652 0.425)
			(end -0.802 0.276)
			(stroke
				(width 0.15)
				(type solid)
			)
			(layer "B.Fab")
		)
		(fp_line
			(start 0.8 0.425)
			(end -0.652 0.425)
			(stroke
				(width 0.15)
				(type solid)
			)
			(layer "B.Fab")
		)
		(fp_line
			(start 0.8 0.425)
			(end 0.8 -0.424)
			(stroke
				(width 0.15)
				(type solid)
			)
			(layer "B.Fab")
		)
		(fp_line
			(start -0.802 0.276)
			(end -0.802 -0.424)
			(stroke
				(width 0.15)
				(type solid)
			)
			(layer "B.Fab")
		)
		(fp_line
			(start 0.8 -0.424)
			(end -0.802 -0.424)
			(stroke
				(width 0.15)
				(type solid)
			)
			(layer "B.Fab")
		)
		(fp_circle
			(center -0.9652 -0.9652)
			(end -0.9144 -0.9652)
			(stroke
				(width 0.15)
				(type solid)
			)
			(fill no)
			(layer "B.Fab")
		)
		(fp_text user "Author: Antmicro"
			(at -1.12 -6.224 90)
			(layer "B.Fab")
			(effects
				(font
					(size 0.7 0.7)
					(thickness 0.15)
				)
				(justify left bottom mirror)
			)
		)
		(fp_text user "License: Apache-2.0"
			(at -1.12 -5.024 90)
			(layer "B.Fab")
			(effects
				(font
					(size 0.7 0.7)
					(thickness 0.15)
				)
				(justify left bottom mirror)
			)
		)
		(fp_text user "${REFERENCE}"
			(at -1.12 -3.824 90)
			(layer "B.Fab")
			(effects
				(font
					(size 0.7 0.7)
					(thickness 0.15)
				)
				(justify left bottom mirror)
			)
		)
		(pad "1" smd rect
			(at -0.5 -0.65 270)
			(size 0.4 0.51)
			(layers "B.Cu" "B.Mask" "B.Paste")
			(net 1300 "Net-(Q34-D)")
			(pinfunction "G")
			(pintype "input")
		)
		(pad "2" smd rect
			(at 0.498 -0.65 270)
			(size 0.4 0.51)
			(layers "B.Cu" "B.Mask" "B.Paste")
			(net 1 "GND")
			(pinfunction "S")
			(pintype "passive")
		)
		(pad "3" smd rect
			(at 0 0.652 270)
			(size 0.4 0.51)
			(layers "B.Cu" "B.Mask" "B.Paste")
			(net 1301 "Net-(Q35-D)")
			(pinfunction "D")
			(pintype "passive")
		)
	)
	(footprint "antmicro-footprints:TP_SMD_0.75mm"
		(layer "B.Cu")
		(at 197.6 118.4 90)
		(property "Reference" "TP69"
			(at 0.4 0.6 0)
			(layer "B.SilkS")
			(effects
				(font
					(size 0.7 0.7)
					(thickness 0.15)
				)
				(justify right top mirror)
			)
		)
		(property "Value" "TP_0.75mm_SMD"
			(at 0 -1.2 90)
			(layer "B.Fab")
			(effects
				(font
					(size 0.7 0.7)
					(thickness 0.15)
				)
				(justify right top mirror)
			)
		)
		(property "Description" "SMT test point"
			(at 0 0 90)
			(layer "B.Fab")
			(hide yes)
			(effects
				(font
					(size 1.27 1.27)
					(thickness 0.15)
				)
				(justify mirror)
			)
		)
		(property "MPN" ""
			(at 0 0 270)
			(unlocked yes)
			(layer "B.Fab")
			(hide yes)
			(effects
				(font
					(size 1 1)
					(thickness 0.15)
				)
				(justify mirror)
			)
		)
		(property "Manufacturer" ""
			(at 0 0 270)
			(unlocked yes)
			(layer "B.Fab")
			(hide yes)
			(effects
				(font
					(size 1 1)
					(thickness 0.15)
				)
				(justify mirror)
			)
		)
		(property "Author" "Antmicro"
			(at 0 0 270)
			(unlocked yes)
			(layer "B.Fab")
			(hide yes)
			(effects
				(font
					(size 1 1)
					(thickness 0.15)
				)
				(justify mirror)
			)
		)
		(property "License" "Apache-2.0"
			(at 0 0 270)
			(unlocked yes)
			(layer "B.Fab")
			(hide yes)
			(effects
				(font
					(size 1 1)
					(thickness 0.15)
				)
				(justify mirror)
			)
		)
		(sheetname "/USB Hub/")
		(sheetfile "usb_hub.kicad_sch")
		(attr exclude_from_pos_files exclude_from_bom)
		(fp_circle
			(center 0 0)
			(end 0.475 0)
			(stroke
				(width 0.05)
				(type default)
			)
			(fill no)
			(layer "B.CrtYd")
		)
		(fp_text user "License: Apache-2.0"
			(at -0.4 -5.101 90)
			(layer "B.Fab")
			(effects
				(font
					(size 0.7 0.7)
					(thickness 0.15)
				)
				(justify right top mirror)
			)
		)
		(fp_text user "Author: Antmicro"
			(at -0.4 -3.901 90)
			(layer "B.Fab")
			(effects
				(font
					(size 0.7 0.7)
					(thickness 0.15)
				)
				(justify right top mirror)
			)
		)
		(fp_text user "${REFERENCE}"
			(at -0.4 -2.7 90)
			(layer "B.Fab")
			(effects
				(font
					(size 0.7 0.7)
					(thickness 0.15)
				)
				(justify right top mirror)
			)
		)
		(pad "1" smd circle
			(at 0 0 90)
			(size 0.75 0.75)
			(layers "B.Cu" "B.Mask")
			(net 1099 "/USB Hub/DP2_VCONN1")
			(pinfunction "1")
			(pintype "passive")
		)
	)
	(footprint "antmicro-footprints:C_0402_1005Metric"
		(layer "B.Cu")
		(at 107.85 70.66 180)
		(descr "Capacitor SMD 0402")
		(tags "capacitor SMD 0402")
		(property "Reference" "C4"
			(at -0.75 -1.44 0)
			(layer "B.SilkS")
			(effects
				(font
					(size 0.7 0.7)
					(thickness 0.15)
				)
				(justify left bottom mirror)
			)
		)
		(property "Value" "C_10u_0402"
			(at -1.022927 -2.155213 0)
			(layer "B.Fab")
			(effects
				(font
					(size 0.7 0.7)
					(thickness 0.15)
				)
				(justify left bottom mirror)
			)
		)
		(property "Datasheet" "https://www.yageo.com/en/Chart/Download/pdf/CC0402MRX5R5BB106"
			(at 0 0 0)
			(layer "B.Fab")
			(hide yes)
			(effects
				(font
					(size 1.27 1.27)
					(thickness 0.15)
				)
				(justify mirror)
			)
		)
		(property "Description" "SMD Multilayer Ceramic Capacitor, 10 µF, 6.3 V, 0402 [1005 Metric], ± 20%, X5R, CC Series"
			(at 0 0 0)
			(layer "B.Fab")
			(hide yes)
			(effects
				(font
					(size 1.27 1.27)
					(thickness 0.15)
				)
				(justify mirror)
			)
		)
		(property "MPN" "CC0402MRX5R5BB106"
			(at 0 0 0)
			(unlocked yes)
			(layer "B.Fab")
			(hide yes)
			(effects
				(font
					(size 1 1)
					(thickness 0.15)
				)
				(justify mirror)
			)
		)
		(property "Manufacturer" "YAGEO"
			(at 0 0 0)
			(unlocked yes)
			(layer "B.Fab")
			(hide yes)
			(effects
				(font
					(size 1 1)
					(thickness 0.15)
				)
				(justify mirror)
			)
		)
		(property "License" "Apache-2.0"
			(at 0 0 0)
			(unlocked yes)
			(layer "B.Fab")
			(hide yes)
			(effects
				(font
					(size 1 1)
					(thickness 0.15)
				)
				(justify mirror)
			)
		)
		(property "Author" "Antmicro"
			(at 0 0 0)
			(unlocked yes)
			(layer "B.Fab")
			(hide yes)
			(effects
				(font
					(size 1 1)
					(thickness 0.15)
				)
				(justify mirror)
			)
		)
		(property "Val" "10u"
			(at 0 0 0)
			(unlocked yes)
			(layer "B.Fab")
			(hide yes)
			(effects
				(font
					(size 1 1)
					(thickness 0.15)
				)
				(justify mirror)
			)
		)
		(property "Voltage" ""
			(at 0 0 0)
			(unlocked yes)
			(layer "B.Fab")
			(hide yes)
			(effects
				(font
					(size 1 1)
					(thickness 0.15)
				)
				(justify mirror)
			)
		)
		(property "Dielectric" "template_dielectric"
			(at 0 0 0)
			(unlocked yes)
			(layer "B.Fab")
			(hide yes)
			(effects
				(font
					(size 1 1)
					(thickness 0.15)
				)
				(justify mirror)
			)
		)
		(sheetname "/SoM_Power/")
		(sheetfile "som_power.kicad_sch")
		(attr smd)
		(fp_rect
			(start -0.925 0.47)
			(end 0.925 -0.47)
			(stroke
				(width 0.05)
				(type default)
			)
			(fill no)
			(layer "B.CrtYd")
		)
		(fp_line
			(start 0.504 0.25)
			(end 0.504 -0.248)
			(stroke
				(width 0.15)
				(type solid)
			)
			(layer "B.Fab")
		)
		(fp_line
			(start 0.504 -0.248)
			(end -0.494 -0.248)
			(stroke
				(width 0.15)
				(type solid)
			)
			(layer "B.Fab")
		)
		(fp_line
			(start -0.494 0.25)
			(end 0.504 0.25)
			(stroke
				(width 0.15)
				(type solid)
			)
			(layer "B.Fab")
		)
		(fp_line
			(start -0.494 -0.248)
			(end -0.494 0.25)
			(stroke
				(width 0.15)
				(type solid)
			)
			(layer "B.Fab")
		)
		(fp_text user "${REFERENCE}"
			(at -0.939 -4.599 0)
			(layer "B.Fab")
			(effects
				(font
					(size 0.7 0.7)
					(thickness 0.15)
				)
				(justify left bottom mirror)
			)
		)
		(fp_text user "Author: Antmicro"
			(at -0.939 -3.399 0)
			(layer "B.Fab")
			(effects
				(font
					(size 0.7 0.7)
					(thickness 0.15)
				)
				(justify left bottom mirror)
			)
		)
		(fp_text user "License: Apache-2.0"
			(at -0.939 -5.799 0)
			(layer "B.Fab")
			(effects
				(font
					(size 0.7 0.7)
					(thickness 0.15)
				)
				(justify left bottom mirror)
			)
		)
		(pad "1" smd roundrect
			(at -0.48 0 180)
			(size 0.59 0.64)
			(layers "B.Cu" "B.Mask" "B.Paste")
			(roundrect_rratio 0.25)
			(net 1 "GND")
			(pintype "passive")
		)
		(pad "2" smd roundrect
			(at 0.48 0 180)
			(size 0.59 0.64)
			(layers "B.Cu" "B.Mask" "B.Paste")
			(roundrect_rratio 0.25)
			(net 213 "+5V_SOM")
			(pintype "passive")
		)
	)
)
